(kicad_pcb
	(version 20260206)
	(generator "pcbnew")
	(generator_version "10.0")
	(general
		(thickness 1.6)
		(legacy_teardrops no)
	)
	(paper "A4")
	(title_block
		(title "peb — Lightning_PEB_BRD.brd")
		(comment 1 "Lightning (Wiwynn / Facebook NVMe JBOF) / footprints 496-502 of 2563")
	)
	(layers
		(0 "F.Cu" signal "TOP")
		(4 "In1.Cu" signal "L2GND")
		(6 "In2.Cu" signal "L3")
		(8 "In3.Cu" signal "L4VCC")
		(10 "In4.Cu" signal "L5VCC")
		(12 "In5.Cu" signal "L6")
		(14 "In6.Cu" signal "L7GND")
		(2 "B.Cu" signal "BOTTOM")
		(9 "F.Adhes" user "F.Adhesive")
		(11 "B.Adhes" user "B.Adhesive")
		(13 "F.Paste" user "Package Geometry/Pastemask Top")
		(15 "B.Paste" user "Package Geometry/Pastemask Bottom")
		(5 "F.SilkS" user "Ref Des/Silkscreen Top")
		(7 "B.SilkS" user "Ref Des/Silkscreen Bottom")
		(1 "F.Mask" user "Board Geometry/Soldermask Top")
		(3 "B.Mask" user "Board Geometry/Soldermask Bottom")
		(17 "Dwgs.User" user "User.Drawings")
		(19 "Cmts.User" user "User.Comments")
		(21 "Eco1.User" user "User.Eco1")
		(23 "Eco2.User" user "User.Eco2")
		(25 "Edge.Cuts" user "Board Geometry/Outline")
		(27 "Margin" user)
		(31 "F.CrtYd" user "Package Geometry/Place Bound Top")
		(29 "B.CrtYd" user "Package Geometry/Place Bound Bottom")
		(35 "F.Fab" user "Ref Des/Assembly Top")
		(33 "B.Fab" user "Ref Des/Assembly Bottom")
	)
	(footprint ""
		(layer "F.Cu")
		(at 339.34146 -43.307)
		(property "Reference" "SW1"
			(at 0 0 0)
			(layer "F.SilkS")
			(hide yes)
			(effects
				(font
					(size 1.27 1.27)
				)
			)
		)
		(property "Value" "SW-TACT-4P-196-GP"
			(at -5.5118 0.2032 0)
			(unlocked yes)
			(layer "F.Fab")
			(hide yes)
			(effects
				(font
					(size 1.016 1.016)
					(thickness 0.1524)
				)
			)
		)
		(property "Device Type" "DTS-63N-V"
			(at -5.5118 -1.3208 0)
			(unlocked yes)
			(layer "F.Fab")
			(hide yes)
			(effects
				(font
					(size 1.016 1.016)
					(thickness 0.1524)
				)
			)
		)
		(duplicate_pad_numbers_are_jumpers no)
		(fp_line
			(start -4.4958 -3.6322)
			(end -4.4958 -2.3622)
			(stroke
				(width 0.4064)
				(type default)
			)
			(layer "F.SilkS")
		)
		(fp_line
			(start -4.2164 -3.3528)
			(end -4.2164 3.3528)
			(stroke
				(width 0.1524)
				(type default)
			)
			(layer "F.SilkS")
		)
		(fp_line
			(start -4.2164 3.3528)
			(end 4.2164 3.3528)
			(stroke
				(width 0.1524)
				(type default)
			)
			(layer "F.SilkS")
		)
		(fp_line
			(start -3.2258 -3.6322)
			(end -4.4958 -3.6322)
			(stroke
				(width 0.4064)
				(type default)
			)
			(layer "F.SilkS")
		)
		(fp_line
			(start 0 -2.54)
			(end 0 -0.762)
			(stroke
				(width 0.1524)
				(type default)
			)
			(layer "F.SilkS")
		)
		(fp_line
			(start 0 -0.762)
			(end 0.508 0.508)
			(stroke
				(width 0.1524)
				(type default)
			)
			(layer "F.SilkS")
		)
		(fp_line
			(start 0 0.762)
			(end 0 2.54)
			(stroke
				(width 0.1524)
				(type default)
			)
			(layer "F.SilkS")
		)
		(fp_line
			(start 4.2164 -3.3528)
			(end -4.2164 -3.3528)
			(stroke
				(width 0.1524)
				(type default)
			)
			(layer "F.SilkS")
		)
		(fp_line
			(start 4.2164 3.3528)
			(end 4.2164 -3.3528)
			(stroke
				(width 0.1524)
				(type default)
			)
			(layer "F.SilkS")
		)
		(fp_circle
			(center -3.24993 -2.249932)
			(end -2.18313 -2.249932)
			(stroke
				(width 0.3048)
				(type default)
			)
			(fill no)
			(layer "F.SilkS")
		)
		(fp_circle
			(center -3.24993 2.249932)
			(end -2.18313 2.249932)
			(stroke
				(width 0.3048)
				(type default)
			)
			(fill no)
			(layer "F.SilkS")
		)
		(fp_circle
			(center 0 -0.762)
			(end 0.0762 -0.762)
			(stroke
				(width 0.1524)
				(type default)
			)
			(fill no)
			(layer "F.SilkS")
		)
		(fp_circle
			(center 0 0.762)
			(end 0.0762 0.762)
			(stroke
				(width 0.1524)
				(type default)
			)
			(fill no)
			(layer "F.SilkS")
		)
		(fp_circle
			(center 3.24993 -2.249932)
			(end 4.31673 -2.249932)
			(stroke
				(width 0.3048)
				(type default)
			)
			(fill no)
			(layer "F.SilkS")
		)
		(fp_circle
			(center 3.24993 2.249932)
			(end 4.31673 2.249932)
			(stroke
				(width 0.3048)
				(type default)
			)
			(fill no)
			(layer "F.SilkS")
		)
		(fp_poly
			(pts
				(xy -3.0988 3.0988) (xy -3.0988 2.605532) (xy -3.9497 2.605532) (xy -3.9497 1.894332) (xy -3.0988 1.894332)
				(xy -3.0988 -1.894332) (xy -3.9497 -1.894332) (xy -3.9497 -2.605532) (xy -3.0988 -2.605532) (xy -3.0988 -3.0988)
				(xy 3.0988 -3.0988) (xy 3.0988 -2.605532) (xy 3.9497 -2.605532) (xy 3.9497 -1.894332) (xy 3.0988 -1.894332)
				(xy 3.0988 1.894332) (xy 3.9497 1.894332) (xy 3.9497 2.605532) (xy 3.0988 2.605532) (xy 3.0988 3.0988)
			)
			(stroke
				(width 0)
				(type default)
			)
			(fill no)
			(layer "F.CrtYd")
		)
		(fp_poly
			(pts
				(xy -4.4704 3.6068) (xy -4.4704 -3.6068) (xy 4.4704 -3.6068) (xy 4.4704 3.6068) (xy 0.00254 3.6068)
				(xy 0.00254 3.0988) (xy 3.0988 3.0988) (xy 3.0988 2.605532) (xy 3.9497 2.605532) (xy 3.9497 1.894332)
				(xy 3.0988 1.894332) (xy 3.0988 -1.894332) (xy 3.9497 -1.894332) (xy 3.9497 -2.605532) (xy 3.0988 -2.605532)
				(xy 3.0988 -3.0988) (xy -3.0988 -3.0988) (xy -3.0988 -2.605532) (xy -3.9497 -2.605532) (xy -3.9497 -1.894332)
				(xy -3.0988 -1.894332) (xy -3.0988 1.894332) (xy -3.9497 1.894332) (xy -3.9497 2.605532) (xy -3.0988 2.605532)
				(xy -3.0988 3.0988) (xy -0.00254 3.0988) (xy -0.00254 3.6068)
			)
			(stroke
				(width 0)
				(type default)
			)
			(fill no)
			(layer "F.CrtYd")
		)
		(fp_rect
			(start -4.4704 3.6068)
			(end 4.4704 -3.6068)
			(stroke
				(width 0)
				(type default)
			)
			(fill no)
			(layer "F.Fab")
		)
		(pad "1" thru_hole circle
			(at -3.24993 -2.249932)
			(size 1.4224 1.4224)
			(drill 1.016)
			(layers "*.Cu" "*.Mask")
			(remove_unused_layers no)
			(net "GND")
			(clearance 0.1524)
			(thermal_gap 0.1524)
		)
		(pad "2" thru_hole circle
			(at 3.24993 -2.249932)
			(size 1.4224 1.4224)
			(drill 1.016)
			(layers "*.Cu" "*.Mask")
			(remove_unused_layers no)
			(net "GND")
			(clearance 0.1524)
			(thermal_gap 0.1524)
		)
		(pad "3" thru_hole circle
			(at -3.24993 2.249932)
			(size 1.4224 1.4224)
			(drill 1.016)
			(layers "*.Cu" "*.Mask")
			(remove_unused_layers no)
			(net "RST_BTN#")
			(clearance 0.1524)
			(thermal_gap 0.1524)
		)
		(pad "4" thru_hole circle
			(at 3.24993 2.249932)
			(size 1.4224 1.4224)
			(drill 1.016)
			(layers "*.Cu" "*.Mask")
			(remove_unused_layers no)
			(net "RST_BTN#")
			(clearance 0.1524)
			(thermal_gap 0.1524)
		)
	)
	(footprint ""
		(layer "F.Cu")
		(at 305.930046 -33.51022)
		(property "Reference" "C17"
			(at 0 0 0)
			(layer "F.SilkS")
			(hide yes)
			(effects
				(font
					(size 1.27 1.27)
				)
			)
		)
		(property "Value" "SCD22U10V2KX-1GP"
			(at 1.1811 -2.7051 0)
			(unlocked yes)
			(layer "F.Fab")
			(hide yes)
			(effects
				(font
					(size 1.016 1.016)
					(thickness 0.1524)
				)
			)
		)
		(property "Device Type" "C402H22"
			(at 1.1811 -4.2291 0)
			(unlocked yes)
			(layer "F.Fab")
			(hide yes)
			(effects
				(font
					(size 1.016 1.016)
					(thickness 0.1524)
				)
			)
		)
		(duplicate_pad_numbers_are_jumpers no)
		(fp_rect
			(start -0.4318 0.9525)
			(end 0.4318 -0.9525)
			(stroke
				(width 0)
				(type default)
			)
			(fill no)
			(layer "F.CrtYd")
		)
		(fp_rect
			(start -0.4318 0.9525)
			(end 0.4318 -0.9525)
			(stroke
				(width 0)
				(type default)
			)
			(fill no)
			(layer "F.Fab")
		)
		(pad "1" smd custom
			(at 0 -0.4445)
			(size 0.1524 0.1524)
			(layers "F.Cu" "F.Mask" "F.Paste")
			(net "PCIE_TX_CAP_P8")
			(options
				(clearance outline)
				(anchor circle)
			)
			(primitives
				(gr_poly
					(pts
						(arc
							(start 0.3048 -0.2032)
							(mid 0.275042 -0.275042)
							(end 0.2032 -0.3048)
						)
						(arc
							(start -0.2032 -0.3048)
							(mid -0.275042 -0.275042)
							(end -0.3048 -0.2032)
						)
						(arc
							(start -0.3048 0.2032)
							(mid -0.275042 0.275042)
							(end -0.2032 0.3048)
						)
						(arc
							(start 0.2032 0.3048)
							(mid 0.275042 0.275042)
							(end 0.3048 0.2032)
						)
					)
					(width 0)
					(fill yes)
				)
			)
		)
		(pad "2" smd custom
			(at 0 0.4445)
			(size 0.1524 0.1524)
			(layers "F.Cu" "F.Mask" "F.Paste")
			(net "PCIE_TX_P8")
			(options
				(clearance outline)
				(anchor circle)
			)
			(primitives
				(gr_poly
					(pts
						(arc
							(start 0.3048 -0.2032)
							(mid 0.275042 -0.275042)
							(end 0.2032 -0.3048)
						)
						(arc
							(start -0.2032 -0.3048)
							(mid -0.275042 -0.275042)
							(end -0.3048 -0.2032)
						)
						(arc
							(start -0.3048 0.2032)
							(mid -0.275042 0.275042)
							(end -0.2032 0.3048)
						)
						(arc
							(start 0.2032 0.3048)
							(mid 0.275042 0.275042)
							(end 0.3048 0.2032)
						)
					)
					(width 0)
					(fill yes)
				)
			)
		)
	)
	(footprint ""
		(layer "F.Cu")
		(at 89.1921 -212.420454 180)
		(property "Reference" "C346"
			(at 0 0 180)
			(layer "F.SilkS")
			(hide yes)
			(effects
				(font
					(size 1.27 1.27)
				)
			)
		)
		(property "Value" "SCD22U10V2KX-1GP"
			(at 1.1811 -2.7051 180)
			(unlocked yes)
			(layer "F.Fab")
			(hide yes)
			(effects
				(font
					(size 1.016 1.016)
					(thickness 0.1524)
				)
			)
		)
		(property "Device Type" "C402H22"
			(at 1.1811 -4.2291 180)
			(unlocked yes)
			(layer "F.Fab")
			(hide yes)
			(effects
				(font
					(size 1.016 1.016)
					(thickness 0.1524)
				)
			)
		)
		(duplicate_pad_numbers_are_jumpers no)
		(fp_rect
			(start -0.4318 0.9525)
			(end 0.4318 -0.9525)
			(stroke
				(width 0)
				(type default)
			)
			(fill no)
			(layer "F.CrtYd")
		)
		(fp_rect
			(start -0.4318 0.9525)
			(end 0.4318 -0.9525)
			(stroke
				(width 0)
				(type default)
			)
			(fill no)
			(layer "F.Fab")
		)
		(pad "1" smd custom
			(at 0 -0.4445 180)
			(size 0.1524 0.1524)
			(layers "F.Cu" "F.Mask" "F.Paste")
			(net "PCIE_TX_CAP_P65")
			(options
				(clearance outline)
				(anchor circle)
			)
			(primitives
				(gr_poly
					(pts
						(arc
							(start 0.3048 -0.2032)
							(mid 0.275042 -0.275042)
							(end 0.2032 -0.3048)
						)
						(arc
							(start -0.2032 -0.3048)
							(mid -0.275042 -0.275042)
							(end -0.3048 -0.2032)
						)
						(arc
							(start -0.3048 0.2032)
							(mid -0.275042 0.275042)
							(end -0.2032 0.3048)
						)
						(arc
							(start 0.2032 0.3048)
							(mid 0.275042 0.275042)
							(end 0.3048 0.2032)
						)
					)
					(width 0)
					(fill yes)
				)
			)
		)
		(pad "2" smd custom
			(at 0 0.4445 180)
			(size 0.1524 0.1524)
			(layers "F.Cu" "F.Mask" "F.Paste")
			(net "PCIE_TX_P65")
			(options
				(clearance outline)
				(anchor circle)
			)
			(primitives
				(gr_poly
					(pts
						(arc
							(start 0.3048 -0.2032)
							(mid 0.275042 -0.275042)
							(end 0.2032 -0.3048)
						)
						(arc
							(start -0.2032 -0.3048)
							(mid -0.275042 -0.275042)
							(end -0.3048 -0.2032)
						)
						(arc
							(start -0.3048 0.2032)
							(mid -0.275042 0.275042)
							(end -0.2032 0.3048)
						)
						(arc
							(start 0.2032 0.3048)
							(mid 0.275042 0.275042)
							(end 0.3048 0.2032)
						)
					)
					(width 0)
					(fill yes)
				)
			)
		)
	)
	(footprint ""
		(layer "F.Cu")
		(at 132.310886 -82.941414 180)
		(property "Reference" "R1848"
			(at 0 0 180)
			(layer "F.SilkS")
			(hide yes)
			(effects
				(font
					(size 1.27 1.27)
				)
			)
		)
		(property "Value" "10MR3F-GP"
			(at -0.0254 -2.5146 180)
			(unlocked yes)
			(layer "F.Fab")
			(hide yes)
			(effects
				(font
					(size 1.016 1.016)
					(thickness 0.1524)
				)
			)
		)
		(property "Device Type" "R603H22"
			(at -0.0254 -4.0386 180)
			(unlocked yes)
			(layer "F.Fab")
			(hide yes)
			(effects
				(font
					(size 1.016 1.016)
					(thickness 0.1524)
				)
			)
		)
		(duplicate_pad_numbers_are_jumpers no)
		(fp_line
			(start 0.2032 0)
			(end 0.4826 0)
			(stroke
				(width 0.2032)
				(type default)
			)
			(layer "F.SilkS")
		)
		(fp_line
			(start -0.4826 0)
			(end -0.2032 0)
			(stroke
				(width 0.2032)
				(type default)
			)
			(layer "F.SilkS")
		)
		(fp_rect
			(start -0.5842 1.3335)
			(end 0.5842 -1.3335)
			(stroke
				(width 0)
				(type default)
			)
			(fill no)
			(layer "F.CrtYd")
		)
		(fp_rect
			(start -0.5842 1.3335)
			(end 0.5842 -1.3335)
			(stroke
				(width 0)
				(type default)
			)
			(fill no)
			(layer "F.Fab")
		)
		(pad "1" smd custom
			(at 0 -0.762 180)
			(size 0.2159 0.2159)
			(layers "F.Cu" "F.Mask" "F.Paste")
			(net "RTC_OSCI")
			(options
				(clearance outline)
				(anchor circle)
			)
			(primitives
				(gr_poly
					(pts
						(arc
							(start -0.3302 -0.4318)
							(mid -0.402042 -0.402042)
							(end -0.4318 -0.3302)
						)
						(arc
							(start -0.4318 0.3302)
							(mid -0.402042 0.402042)
							(end -0.3302 0.4318)
						)
						(arc
							(start 0.3302 0.4318)
							(mid 0.402042 0.402042)
							(end 0.4318 0.3302)
						)
						(arc
							(start 0.4318 -0.3302)
							(mid 0.402042 -0.402042)
							(end 0.3302 -0.4318)
						)
					)
					(width 0)
					(fill yes)
				)
			)
		)
		(pad "2" smd custom
			(at 0 0.762 180)
			(size 0.2159 0.2159)
			(layers "F.Cu" "F.Mask" "F.Paste")
			(net "RTC_OSCO")
			(options
				(clearance outline)
				(anchor circle)
			)
			(primitives
				(gr_poly
					(pts
						(arc
							(start -0.3302 -0.4318)
							(mid -0.402042 -0.402042)
							(end -0.4318 -0.3302)
						)
						(arc
							(start -0.4318 0.3302)
							(mid -0.402042 0.402042)
							(end -0.3302 0.4318)
						)
						(arc
							(start 0.3302 0.4318)
							(mid 0.402042 0.402042)
							(end 0.4318 0.3302)
						)
						(arc
							(start 0.4318 -0.3302)
							(mid 0.402042 -0.402042)
							(end 0.3302 -0.4318)
						)
					)
					(width 0)
					(fill yes)
				)
			)
		)
	)
	(footprint ""
		(layer "F.Cu")
		(at 24.395684 -107.95762)
		(property "Reference" "R9047"
			(at 0 0 0)
			(layer "F.SilkS")
			(hide yes)
			(effects
				(font
					(size 1.27 1.27)
				)
			)
		)
		(property "Value" "56R2F"
			(at 0.064008 -3.993896 0)
			(unlocked yes)
			(layer "F.Fab")
			(hide yes)
			(effects
				(font
					(size 1.016 1.016)
					(thickness 0.1524)
				)
			)
		)
		(property "Device Type" "R402H14"
			(at 0.064008 -5.517896 0)
			(unlocked yes)
			(layer "F.Fab")
			(hide yes)
			(effects
				(font
					(size 1.016 1.016)
					(thickness 0.1524)
				)
			)
		)
		(duplicate_pad_numbers_are_jumpers no)
		(fp_line
			(start -0.508 -0.9398)
			(end -0.508 0.9398)
			(stroke
				(width 0.1524)
				(type default)
			)
			(layer "F.SilkS")
		)
		(fp_line
			(start 0.508 -0.9398)
			(end -0.508 -0.9398)
			(stroke
				(width 0.1524)
				(type default)
			)
			(layer "F.SilkS")
		)
		(fp_rect
			(start -0.508 0.9398)
			(end 0.508 -0.9398)
			(stroke
				(width 0)
				(type default)
			)
			(fill no)
			(layer "F.CrtYd")
		)
		(fp_rect
			(start -0.508 0.9398)
			(end 0.508 -0.9398)
			(stroke
				(width 0)
				(type default)
			)
			(fill no)
			(layer "F.Fab")
		)
		(pad "1" smd custom
			(at 0 -0.4445)
			(size 0.1397 0.1397)
			(layers "F.Cu" "F.Mask" "F.Paste")
			(net "BMC_REFCLK_N")
			(options
				(clearance outline)
				(anchor circle)
			)
			(primitives
				(gr_poly
					(pts
						(arc
							(start -0.1778 -0.2794)
							(mid -0.249642 -0.249642)
							(end -0.2794 -0.1778)
						)
						(arc
							(start -0.2794 0.1778)
							(mid -0.249642 0.249642)
							(end -0.1778 0.2794)
						)
						(arc
							(start 0.1778 0.2794)
							(mid 0.249642 0.249642)
							(end 0.2794 0.1778)
						)
						(arc
							(start 0.2794 -0.1778)
							(mid 0.249642 -0.249642)
							(end 0.1778 -0.2794)
						)
					)
					(width 0)
					(fill yes)
				)
			)
		)
		(pad "2" smd custom
			(at 0 0.4445)
			(size 0.1397 0.1397)
			(layers "F.Cu" "F.Mask" "F.Paste")
			(net "GND")
			(options
				(clearance outline)
				(anchor circle)
			)
			(primitives
				(gr_poly
					(pts
						(arc
							(start -0.1778 -0.2794)
							(mid -0.249642 -0.249642)
							(end -0.2794 -0.1778)
						)
						(arc
							(start -0.2794 0.1778)
							(mid -0.249642 0.249642)
							(end -0.1778 0.2794)
						)
						(arc
							(start 0.1778 0.2794)
							(mid 0.249642 0.249642)
							(end 0.2794 0.1778)
						)
						(arc
							(start 0.2794 -0.1778)
							(mid 0.249642 -0.249642)
							(end 0.1778 -0.2794)
						)
					)
					(width 0)
					(fill yes)
				)
			)
		)
	)
	(footprint ""
		(layer "F.Cu")
		(at 49.788572 -50.306224)
		(property "Reference" "R498"
			(at 0 0 0)
			(layer "F.SilkS")
			(hide yes)
			(effects
				(font
					(size 1.27 1.27)
				)
			)
		)
		(property "Value" "33K2R2F-GP"
			(at 0.064008 -3.993896 0)
			(unlocked yes)
			(layer "F.Fab")
			(hide yes)
			(effects
				(font
					(size 1.016 1.016)
					(thickness 0.1524)
				)
			)
		)
		(property "Device Type" "R402H16"
			(at 0.064008 -5.517896 0)
			(unlocked yes)
			(layer "F.Fab")
			(hide yes)
			(effects
				(font
					(size 1.016 1.016)
					(thickness 0.1524)
				)
			)
		)
		(duplicate_pad_numbers_are_jumpers no)
		(fp_line
			(start -0.508 -0.9398)
			(end -0.508 0.9398)
			(stroke
				(width 0.1524)
				(type default)
			)
			(layer "F.SilkS")
		)
		(fp_line
			(start 0.508 -0.9398)
			(end -0.508 -0.9398)
			(stroke
				(width 0.1524)
				(type default)
			)
			(layer "F.SilkS")
		)
		(fp_rect
			(start -0.508 0.9398)
			(end 0.508 -0.9398)
			(stroke
				(width 0)
				(type default)
			)
			(fill no)
			(layer "F.CrtYd")
		)
		(fp_rect
			(start -0.508 0.9398)
			(end 0.508 -0.9398)
			(stroke
				(width 0)
				(type default)
			)
			(fill no)
			(layer "F.Fab")
		)
		(pad "1" smd custom
			(at 0 -0.4445)
			(size 0.1397 0.1397)
			(layers "F.Cu" "F.Mask" "F.Paste")
			(net "NVM_SK_R")
			(options
				(clearance outline)
				(anchor circle)
			)
			(primitives
				(gr_poly
					(pts
						(arc
							(start -0.1778 -0.2794)
							(mid -0.249642 -0.249642)
							(end -0.2794 -0.1778)
						)
						(arc
							(start -0.2794 0.1778)
							(mid -0.249642 0.249642)
							(end -0.1778 0.2794)
						)
						(arc
							(start 0.1778 0.2794)
							(mid 0.249642 0.249642)
							(end 0.2794 0.1778)
						)
						(arc
							(start 0.2794 -0.1778)
							(mid 0.249642 -0.249642)
							(end 0.1778 -0.2794)
						)
					)
					(width 0)
					(fill yes)
				)
			)
		)
		(pad "2" smd custom
			(at 0 0.4445)
			(size 0.1397 0.1397)
			(layers "F.Cu" "F.Mask" "F.Paste")
			(net "GND")
			(options
				(clearance outline)
				(anchor circle)
			)
			(primitives
				(gr_poly
					(pts
						(arc
							(start -0.1778 -0.2794)
							(mid -0.249642 -0.249642)
							(end -0.2794 -0.1778)
						)
						(arc
							(start -0.2794 0.1778)
							(mid -0.249642 0.249642)
							(end -0.1778 0.2794)
						)
						(arc
							(start 0.1778 0.2794)
							(mid 0.249642 0.249642)
							(end 0.2794 0.1778)
						)
						(arc
							(start 0.2794 -0.1778)
							(mid 0.249642 -0.249642)
							(end 0.1778 -0.2794)
						)
					)
					(width 0)
					(fill yes)
				)
			)
		)
	)
	(footprint ""
		(layer "F.Cu")
		(at 9.4742 -179.9336)
		(property "Reference" "CA1"
			(at 0 0 0)
			(layer "F.SilkS")
			(hide yes)
			(effects
				(font
					(size 1.27 1.27)
				)
			)
		)
		(property "Value" "SC2D2U25V5KX-2-GP"
			(at -0.0762 -6.1214 0)
			(unlocked yes)
			(layer "F.Fab")
			(hide yes)
			(effects
				(font
					(size 1.016 1.016)
					(thickness 0.1524)
				)
			)
		)
		(property "Device Type" "C805H54"
			(at -0.0762 -8.1534 0)
			(unlocked yes)
			(layer "F.Fab")
			(hide yes)
			(effects
				(font
					(size 1.016 1.016)
					(thickness 0.1524)
				)
			)
		)
		(duplicate_pad_numbers_are_jumpers no)
		(fp_line
			(start 0.635 0)
			(end -0.635 0)
			(stroke
				(width 0.508)
				(type default)
			)
			(layer "F.SilkS")
		)
		(fp_rect
			(start -0.9652 1.778)
			(end 0.9652 -1.778)
			(stroke
				(width 0)
				(type default)
			)
			(fill no)
			(layer "F.CrtYd")
		)
		(fp_poly
			(pts
				(xy -0.9652 -1.778) (xy 0.9652 -1.778) (xy 0.9652 1.778) (xy -0.9652 1.778)
			)
			(stroke
				(width 0)
				(type default)
			)
			(fill no)
			(layer "F.Fab")
		)
		(pad "1" smd rect
			(at 0 -0.9652)
			(size 1.397 1.143)
			(layers "F.Cu" "F.Mask" "F.Paste")
			(net "MB0_P12V_PWRGOOD")
		)
		(pad "2" smd rect
			(at 0 0.9652)
			(size 1.397 1.143)
			(layers "F.Cu" "F.Mask" "F.Paste")
			(net "AGND_CURRENT_MON")
		)
	)
)
